# T6G (Grand Teton) — schematic netlist excerpt (pin names and nets, part order shuffled) for the footprints in the layout excerpt that follows; sources: Cadence DE-HDL packaged netlist, KiCad conversion of 04192023_DAF0TMB3IC0_F0TG_MB_C_brd_V02_OCP.brd

PR6806  Q_RES  1K 1% EMPTY  pkg 0402LF  page 364 : A = P3V3_AUX ; B = P0V9_RETIMER_CPU1_SVID_CLK
PC2261  Q_CAP  22UF 16V 20% X6S  pkg C0805  page 190 : A = SW_P3V3_AUX_FLT ; B = GND
R3267  Q_RES  68K 1% EMPTY  pkg 0402LF  page 111 : A = FM_P2E_FGB ; B = GND

(kicad_pcb
	(version 20260206)
	(generator "pcbnew")
	(generator_version "10.0")
	(general
		(thickness 1.6)
		(legacy_teardrops no)
	)
	(paper "A4")
	(title_block
		(title "04192023_DAF0TMB3IC0_F0TG_MB_C_brd_V02_OCP.brd")
		(comment 1 "Grand Teton / footprints 2532-2534 of 8354")
	)
	(layers
		(0 "F.Cu" signal "TOP")
		(4 "In1.Cu" signal "GND")
		(6 "In2.Cu" signal "IN1")
		(8 "In3.Cu" signal "GND1")
		(10 "In4.Cu" signal "IN2")
		(12 "In5.Cu" signal "GND2")
		(14 "In6.Cu" signal "IN3")
		(16 "In7.Cu" signal "GND3")
		(18 "In8.Cu" signal "VCC")
		(20 "In9.Cu" signal "VCC1")
		(22 "In10.Cu" signal "GND4")
		(24 "In11.Cu" signal "IN4")
		(26 "In12.Cu" signal "GND5")
		(28 "In13.Cu" signal "IN5")
		(30 "In14.Cu" signal "GND6")
		(32 "In15.Cu" signal "IN6")
		(34 "In16.Cu" signal "GND7")
		(2 "B.Cu" signal "BOTTOM")
		(9 "F.Adhes" user "F.Adhesive")
		(11 "B.Adhes" user "B.Adhesive")
		(13 "F.Paste" user "Package Geometry/Pastemask Top")
		(15 "B.Paste" user "Package Geometry/Pastemask Bottom")
		(5 "F.SilkS" user "Ref Des/Silkscreen Top")
		(7 "B.SilkS" user "Ref Des/Silkscreen Bottom")
		(1 "F.Mask" user "Board Geometry/Soldermask Top")
		(3 "B.Mask" user "Board Geometry/Soldermask Bottom")
		(17 "Dwgs.User" user "User.Drawings")
		(19 "Cmts.User" user "User.Comments")
		(21 "Eco1.User" user "User.Eco1")
		(23 "Eco2.User" user "User.Eco2")
		(25 "Edge.Cuts" user "Board Geometry/Outline")
		(27 "Margin" user)
		(31 "F.CrtYd" user "Package Geometry/Place Bound Top")
		(29 "B.CrtYd" user "Package Geometry/Place Bound Bottom")
		(35 "F.Fab" user "Ref Des/Assembly Top")
		(33 "B.Fab" user "Ref Des/Assembly Bottom")
	)
	(footprint ""
		(layer "F.Cu")
		(at 34.379662 -429.790098 90)
		(property "Reference" "R3267"
			(at 0 0 90)
			(layer "F.SilkS")
			(hide yes)
			(effects
				(font
					(size 1.27 1.27)
				)
			)
		)
		(property "Value" ""
			(at 0 0 90)
			(layer "F.Fab")
			(effects
				(font
					(size 1.27 1.27)
				)
			)
		)
		(duplicate_pad_numbers_are_jumpers no)
		(fp_line
			(start 0.7874 -0.4064)
			(end 0.7874 0.4064)
			(stroke
				(width 0.1524)
				(type default)
			)
			(layer "F.SilkS")
		)
		(fp_line
			(start -0.7874 -0.4064)
			(end 0.7874 -0.4064)
			(stroke
				(width 0.1524)
				(type default)
			)
			(layer "F.SilkS")
		)
		(fp_line
			(start 0.7874 0.4064)
			(end -0.7874 0.4064)
			(stroke
				(width 0.1524)
				(type default)
			)
			(layer "F.SilkS")
		)
		(fp_line
			(start -0.7874 0.4064)
			(end -0.7874 -0.4064)
			(stroke
				(width 0.1524)
				(type default)
			)
			(layer "F.SilkS")
		)
		(fp_line
			(start -0.12065 -0.305054)
			(end -0.12065 -0.2794)
			(stroke
				(width 0.1)
				(type default)
			)
			(layer "F.Fab")
		)
		(fp_line
			(start -0.67945 -0.305054)
			(end -0.12065 -0.305054)
			(stroke
				(width 0.1)
				(type default)
			)
			(layer "F.Fab")
		)
		(fp_line
			(start 0.67945 -0.3048)
			(end 0.67945 0.3048)
			(stroke
				(width 0.1)
				(type default)
			)
			(layer "F.Fab")
		)
		(fp_line
			(start 0.12065 -0.3048)
			(end 0.67945 -0.3048)
			(stroke
				(width 0.1)
				(type default)
			)
			(layer "F.Fab")
		)
		(fp_line
			(start 0.12065 -0.2794)
			(end 0.12065 -0.3048)
			(stroke
				(width 0.1)
				(type default)
			)
			(layer "F.Fab")
		)
		(fp_line
			(start -0.12065 -0.2794)
			(end 0.12065 -0.2794)
			(stroke
				(width 0.1)
				(type default)
			)
			(layer "F.Fab")
		)
		(fp_line
			(start 0.120396 0.2794)
			(end -0.12065 0.2794)
			(stroke
				(width 0.1)
				(type default)
			)
			(layer "F.Fab")
		)
		(fp_line
			(start -0.12065 0.2794)
			(end -0.12065 0.3048)
			(stroke
				(width 0.1)
				(type default)
			)
			(layer "F.Fab")
		)
		(fp_line
			(start 0.67945 0.3048)
			(end 0.120396 0.3048)
			(stroke
				(width 0.1)
				(type default)
			)
			(layer "F.Fab")
		)
		(fp_line
			(start 0.120396 0.3048)
			(end 0.120396 0.2794)
			(stroke
				(width 0.1)
				(type default)
			)
			(layer "F.Fab")
		)
		(fp_line
			(start -0.12065 0.3048)
			(end -0.67945 0.3048)
			(stroke
				(width 0.1)
				(type default)
			)
			(layer "F.Fab")
		)
		(fp_line
			(start -0.67945 0.3048)
			(end -0.67945 -0.305054)
			(stroke
				(width 0.1)
				(type default)
			)
			(layer "F.Fab")
		)
		(pad "1" smd circle
			(at -0.40005 0 90)
			(size 0 0)
			(layers "F.Cu" "F.Mask" "F.Paste")
			(net "FM_P2E_FGB")
		)
		(pad "2" smd circle
			(at 0.40005 0 90)
			(size 0 0)
			(layers "F.Cu" "F.Mask" "F.Paste")
			(net "GND")
		)
	)
	(footprint ""
		(layer "F.Cu")
		(at 446.258442 -53.188108 90)
		(property "Reference" "PC2261"
			(at 0 0 90)
			(layer "F.SilkS")
			(hide yes)
			(effects
				(font
					(size 1.27 1.27)
				)
			)
		)
		(property "Value" ""
			(at 0 0 90)
			(layer "F.Fab")
			(effects
				(font
					(size 1.27 1.27)
				)
			)
		)
		(duplicate_pad_numbers_are_jumpers no)
		(fp_line
			(start 1.524 -0.762)
			(end 1.524 0.762)
			(stroke
				(width 0.1524)
				(type default)
			)
			(layer "F.SilkS")
		)
		(fp_line
			(start -1.524 -0.762)
			(end 1.524 -0.762)
			(stroke
				(width 0.1524)
				(type default)
			)
			(layer "F.SilkS")
		)
		(fp_line
			(start 1.524 0.762)
			(end -1.524 0.762)
			(stroke
				(width 0.1524)
				(type default)
			)
			(layer "F.SilkS")
		)
		(fp_line
			(start -1.524 0.762)
			(end -1.524 -0.762)
			(stroke
				(width 0.1524)
				(type default)
			)
			(layer "F.SilkS")
		)
		(fp_line
			(start 1.1049 -0.724916)
			(end -1.1049 -0.724916)
			(stroke
				(width 0.1)
				(type default)
			)
			(layer "F.Fab")
		)
		(fp_line
			(start -1.1049 -0.724916)
			(end -1.1049 0.724916)
			(stroke
				(width 0.1)
				(type default)
			)
			(layer "F.Fab")
		)
		(fp_line
			(start 1.1049 0.724916)
			(end 1.1049 -0.724916)
			(stroke
				(width 0.1)
				(type default)
			)
			(layer "F.Fab")
		)
		(fp_line
			(start -1.1049 0.724916)
			(end 1.1049 0.724916)
			(stroke
				(width 0.1)
				(type default)
			)
			(layer "F.Fab")
		)
		(pad "1" smd rect
			(at -0.889 0 270)
			(size 1.016 1.27)
			(layers "F.Cu" "F.Mask" "F.Paste")
			(net "SW_P3V3_AUX_FLT")
		)
		(pad "2" smd rect
			(at 0.889 0 270)
			(size 1.016 1.27)
			(layers "F.Cu" "F.Mask" "F.Paste")
			(net "GND")
		)
	)
	(footprint ""
		(layer "F.Cu")
		(at 20.480782 -410.564584 180)
		(property "Reference" "PR6806"
			(at 0 0 180)
			(layer "F.SilkS")
			(hide yes)
			(effects
				(font
					(size 1.27 1.27)
				)
			)
		)
		(property "Value" ""
			(at 0 0 180)
			(layer "F.Fab")
			(effects
				(font
					(size 1.27 1.27)
				)
			)
		)
		(duplicate_pad_numbers_are_jumpers no)
		(fp_line
			(start 0.7874 0.4064)
			(end -0.7874 0.4064)
			(stroke
				(width 0.1524)
				(type default)
			)
			(layer "F.SilkS")
		)
		(fp_line
			(start 0.7874 -0.4064)
			(end 0.7874 0.4064)
			(stroke
				(width 0.1524)
				(type default)
			)
			(layer "F.SilkS")
		)
		(fp_line
			(start -0.7874 0.4064)
			(end -0.7874 -0.4064)
			(stroke
				(width 0.1524)
				(type default)
			)
			(layer "F.SilkS")
		)
		(fp_line
			(start -0.7874 -0.4064)
			(end 0.7874 -0.4064)
			(stroke
				(width 0.1524)
				(type default)
			)
			(layer "F.SilkS")
		)
		(fp_line
			(start 0.67945 0.3048)
			(end 0.120396 0.3048)
			(stroke
				(width 0.1)
				(type default)
			)
			(layer "F.Fab")
		)
		(fp_line
			(start 0.67945 -0.3048)
			(end 0.67945 0.3048)
			(stroke
				(width 0.1)
				(type default)
			)
			(layer "F.Fab")
		)
		(fp_line
			(start 0.12065 -0.2794)
			(end 0.12065 -0.3048)
			(stroke
				(width 0.1)
				(type default)
			)
			(layer "F.Fab")
		)
		(fp_line
			(start 0.12065 -0.3048)
			(end 0.67945 -0.3048)
			(stroke
				(width 0.1)
				(type default)
			)
			(layer "F.Fab")
		)
		(fp_line
			(start 0.120396 0.3048)
			(end 0.120396 0.2794)
			(stroke
				(width 0.1)
				(type default)
			)
			(layer "F.Fab")
		)
		(fp_line
			(start 0.120396 0.2794)
			(end -0.12065 0.2794)
			(stroke
				(width 0.1)
				(type default)
			)
			(layer "F.Fab")
		)
		(fp_line
			(start -0.12065 0.3048)
			(end -0.67945 0.3048)
			(stroke
				(width 0.1)
				(type default)
			)
			(layer "F.Fab")
		)
		(fp_line
			(start -0.12065 0.2794)
			(end -0.12065 0.3048)
			(stroke
				(width 0.1)
				(type default)
			)
			(layer "F.Fab")
		)
		(fp_line
			(start -0.12065 -0.2794)
			(end 0.12065 -0.2794)
			(stroke
				(width 0.1)
				(type default)
			)
			(layer "F.Fab")
		)
		(fp_line
			(start -0.12065 -0.305054)
			(end -0.12065 -0.2794)
			(stroke
				(width 0.1)
				(type default)
			)
			(layer "F.Fab")
		)
		(fp_line
			(start -0.67945 0.3048)
			(end -0.67945 -0.305054)
			(stroke
				(width 0.1)
				(type default)
			)
			(layer "F.Fab")
		)
		(fp_line
			(start -0.67945 -0.305054)
			(end -0.12065 -0.305054)
			(stroke
				(width 0.1)
				(type default)
			)
			(layer "F.Fab")
		)
		(pad "1" smd circle
			(at -0.40005 0 180)
			(size 0 0)
			(layers "F.Cu" "F.Mask" "F.Paste")
			(net "P3V3_AUX")
		)
		(pad "2" smd circle
			(at 0.40005 0 180)
			(size 0 0)
			(layers "F.Cu" "F.Mask" "F.Paste")
			(net "P0V9_RETIMER_CPU1_SVID_CLK")
		)
	)
)
